FILE_TYPE = CONNECTIVITY;
{Allegro Design Entry HDL 17.4-2019 S026 (4007227) 1/17/2022}
"PAGE_NUMBER" = 86;
0"NC";
1"GND\g";
2"GND\g";
3"P3V3\g";
4"M_B_CPU0_SB_CB<7:0>";
5"M_B_CPU0_SB_DQ<31:0>";
6"M_B_CPU0_SA_DQ<31:0>";
7"M_B_CPU0_SA_CB<7:0>";
8"M_B_CPU0_SA_CA<6:0>";
9"M_B_CPU0_SB_CA<6:0>";
10"M_B_CPU0_SA_DQS_DN<9:0>";
11"M_B_CPU0_SA_DQS_DP<9:0>";
12"M_B_CPU0_SB_DQS_DP<9:0>";
13"M_B_CPU0_SB_DQS_DN<9:0>";
14"P3V3_AUX\g";
15"I3C_SPD_DDRB_CPU0_SDA";
16"I3C_SPD_DDRAF_CPU0_SCL";
17"PWRGD_CHB_CPU0_DIMM";
18"PD_CHB_CPU0_DIMM_SAA";
19"M_B_CPU0_SB_CB<3>";
20"M_B_CPU0_SB_CB<0>";
21"M_B_CPU0_SB_CB<1>";
22"M_B_CPU0_SB_CB<2>";
23"M_B_CPU0_SB_DQ<24>";
24"M_B_CPU0_SB_DQ<30>";
25"M_B_CPU0_CLK_DP<0>";
26"M_B_CPU0_SB_CS_N<0>";
27"M_B_CPU0_SA_PAR";
28"M_B_CPU0_SB_PAR";
29"M_B_CPU0_SA_DQ<26>";
30"M_B_CPU0_SA_DQ<25>";
31"M_B_CPU0_SB_DQS_DP<9>";
32"M_B_CPU0_SB_DQS_DN<9>";
33"M_B_CPU0_SA_DQS_DN<0>";
34"M_B_CPU0_SA_DQS_DP<0>";
35"M_B_CPU0_SA_DQS_DP<9>";
36"M_B_CPU0_SA_DQS_DN<9>";
37"M_B_CPU0_SA_DQS_DP<8>";
38"M_B_CPU0_SA_DQS_DN<8>";
39"M_B_CPU0_SB_DQS_DN<7>";
40"M_B_CPU0_SA_DQS_DP<7>";
41"M_B_CPU0_SB_DQS_DP<6>";
42"M_B_CPU0_SB_DQS_DN<6>";
43"M_B_CPU0_SA_DQS_DN<6>";
44"M_B_CPU0_SB_DQS_DP<5>";
45"M_B_CPU0_SB_DQS_DN<5>";
46"M_B_CPU0_SA_DQS_DP<5>";
47"M_B_CPU0_SA_DQS_DN<5>";
48"M_B_CPU0_SB_DQS_DP<4>";
49"M_B_CPU0_SB_DQS_DN<4>";
50"M_B_CPU0_SA_DQS_DP<4>";
51"M_B_CPU0_SA_DQS_DN<4>";
52"M_B_CPU0_SB_DQS_DP<3>";
53"M_B_CPU0_SB_DQS_DN<3>";
54"M_B_CPU0_SA_DQS_DP<3>";
55"M_B_CPU0_SA_DQS_DN<3>";
56"M_B_CPU0_SB_DQS_DP<2>";
57"M_B_CPU0_SB_DQS_DN<2>";
58"M_B_CPU0_SA_DQS_DP<2>";
59"M_B_CPU0_SA_DQS_DN<2>";
60"M_B_CPU0_SB_DQS_DP<1>";
61"M_B_CPU0_SB_DQS_DN<1>";
62"M_B_CPU0_SA_DQS_DP<1>";
63"M_B_CPU0_SA_DQS_DN<1>";
64"M_B_CPU0_SB_DQS_DP<0>";
65"M_B_CPU0_SB_DQS_DN<0>";
66"M_B_CPU0_SB_DQS_DP<7>";
67"M_B_CPU0_SB_DQS_DN<8>";
68"M_B_CPU0_SB_DQS_DP<8>";
69"M_B_CPU0_SA_DQS_DP<6>";
70"M_B_CPU0_SA_DQS_DN<7>";
71"M_B_CPU0_SA_DQ<27>";
72"M_B_CPU0_SA_DQ<28>";
73"M_B_CPU0_SA_CA<6>";
74"M_B_CPU0_SA_DQ<19>";
75"M_B_CPU0_SA_DQ<18>";
76"M_B_CPU0_SA_RSP<0>";
77"M_B_CPU0_SB_DQ<0>";
78"M_B_CPU0_SB_DQ<1>";
79"M_B_CPU0_SB_DQ<2>";
80"M_B_CPU0_SB_DQ<3>";
81"M_B_CPU0_SB_DQ<5>";
82"M_B_CPU0_SB_DQ<6>";
83"M_B_CPU0_SB_DQ<7>";
84"M_B_CPU0_SB_DQ<8>";
85"M_B_CPU0_SB_DQ<9>";
86"M_B_CPU0_SB_DQ<10>";
87"M_B_CPU0_SB_DQ<11>";
88"M_B_CPU0_SB_DQ<12>";
89"M_B_CPU0_SB_DQ<13>";
90"M_B_CPU0_SB_DQ<14>";
91"M_B_CPU0_SB_DQ<15>";
92"M_B_CPU0_SB_DQ<16>";
93"M_B_CPU0_SB_DQ<17>";
94"M_B_CPU0_SB_DQ<18>";
95"M_B_CPU0_SB_DQ<19>";
96"M_B_CPU0_SB_DQ<20>";
97"M_B_CPU0_SB_DQ<21>";
98"M_B_CPU0_SB_DQ<22>";
99"M_B_CPU0_SB_DQ<23>";
100"M_B_CPU0_SB_DQ<25>";
101"M_B_CPU0_SB_DQ<26>";
102"M_B_CPU0_SB_DQ<27>";
103"M_B_CPU0_SB_DQ<28>";
104"M_B_CPU0_SB_DQ<29>";
105"M_B_CPU0_SB_DQ<31>";
106"M_B_CPU0_SA_DQ<0>";
107"M_B_CPU0_SA_DQ<1>";
108"M_B_CPU0_SA_DQ<2>";
109"M_B_CPU0_SA_DQ<3>";
110"M_B_CPU0_SA_DQ<4>";
111"M_B_CPU0_SA_DQ<5>";
112"M_B_CPU0_SA_DQ<6>";
113"M_B_CPU0_SA_DQ<7>";
114"M_B_CPU0_SA_DQ<8>";
115"M_B_CPU0_SA_DQ<9>";
116"M_B_CPU0_SA_DQ<10>";
117"M_B_CPU0_SA_DQ<11>";
118"M_B_CPU0_SA_DQ<12>";
119"M_B_CPU0_SA_DQ<13>";
120"M_B_CPU0_SA_DQ<14>";
121"M_B_CPU0_SA_DQ<15>";
122"M_B_CPU0_SA_DQ<16>";
123"M_B_CPU0_SA_DQ<17>";
124"M_B_CPU0_SA_DQ<20>";
125"M_B_CPU0_SA_DQ<21>";
126"M_B_CPU0_SA_DQ<22>";
127"M_B_CPU0_SA_DQ<23>";
128"M_B_CPU0_SA_DQ<24>";
129"M_B_CPU0_SA_DQ<29>";
130"M_B_CPU0_SA_DQ<30>";
131"M_B_CPU0_SB_CS_N<1>";
132"M_B_CPU0_SA_CS_N<1>";
133"M_B_CPU0_SA_CS_N<0>";
134"M_B_CPU0_CLK_DN<0>";
135"M_B_CPU0_SB_CB<6>";
136"M_B_CPU0_SA_CB<0>";
137"M_B_CPU0_SA_CB<2>";
138"M_B_CPU0_SA_CB<3>";
139"M_B_CPU0_SA_CB<5>";
140"M_B_CPU0_SA_CB<6>";
141"M_B_CPU0_SB_CA<6>";
142"M_B_CPU0_SB_CA<5>";
143"M_B_CPU0_SA_CA<5>";
144"M_B_CPU0_SB_CA<4>";
145"M_B_CPU0_SA_CA<4>";
146"M_B_CPU0_SB_CA<3>";
147"M_B_CPU0_SA_CA<3>";
148"M_B_CPU0_SB_CA<2>";
149"M_B_CPU0_SA_CA<2>";
150"M_B_CPU0_SB_CA<1>";
151"M_B_CPU0_SA_CA<1>";
152"M_B_CPU0_SB_CA<0>";
153"M_B_CPU0_SA_CA<0>";
154"M_B_CPU0_SB_CB<7>";
155"M_B_CPU0_SA_CB<1>";
156"M_B_CPU0_SA_CB<4>";
157"M_B_CPU0_SA_CB<7>";
158"M_B_CPU0_SA_DQ<31>";
159"PD_CHB_CPU0_DIMM_SAA";
160"M_B_CPU0_SB_RSP<0>";
161"M_B_CPU0_SB_DQ<4>";
162"PWRGD_CHAF_CPU0";
163"GND\g";
164"GND\g";
165"GND\g";
166"P12V_MEM_CPU0\g";
167"M_B_CPU0_SB_CB<4>";
168"M_B_CPU0_SB_CB<5>";
169"I3C_SPD_DDRB_CPU0_SCL";
170"I3C_SPD_DDRAF_CPU0_SDA";
171"M_B_CPU0_RESET_N";
172"M_B_CPU0_ALERT_N";
%"GND"
"1","(-2125,1825)","0","mstr_symbols","I150";
;
VOLTAGE"0.0"
CDS_LIB"mstr_symbols"
SIZE"1B"
BODY_TYPE"PLUMBING"
HDL_POWER"GND";
"A\NAC"163;
%"GND"
"1","(-325,1650)","0","mstr_symbols","I152";
;
VOLTAGE"0.0"
CDS_LIB"mstr_symbols"
SIZE"1B"
BODY_TYPE"PLUMBING"
HDL_POWER"GND";
"A\NAC"164;
%"VCC_CORE"
"1","(-8925,3575)","0","mstr_symbols","I177";
;
HDL_POWER"P3V3_AUX"
ROOM"PVCCINFAON_CPU0_CTRL"
VOLTAGE"3.3"
CDS_LIB"mstr_symbols";
"A"14;
%"TAP"
"1","(-7950,3375)","2","mstr_standard","I187";
;
CDS_LIB"mstr_standard"
BODY_TYPE"PLUMBING"
HDL_TAP"TRUE";
"B \NAC \NWC"4;
"S \NAC"
BN"1"21;
%"TAP"
"1","(-7950,3425)","2","mstr_standard","I188";
;
CDS_LIB"mstr_standard"
BODY_TYPE"PLUMBING"
HDL_TAP"TRUE";
"B \NAC \NWC"4;
"S \NAC"
BN"2"22;
%"TAP"
"1","(-7950,3325)","2","mstr_standard","I189";
;
CDS_LIB"mstr_standard"
BODY_TYPE"PLUMBING"
HDL_TAP"TRUE";
"B \NAC \NWC"4;
"S \NAC"
BN"0"20;
%"TAP"
"1","(-7950,3475)","2","mstr_standard","I190";
;
CDS_LIB"mstr_standard"
BODY_TYPE"PLUMBING"
HDL_TAP"TRUE";
"B \NAC \NWC"4;
"S \NAC"
BN"3"19;
%"TAP"
"1","(-7950,3525)","2","mstr_standard","I191";
;
CDS_LIB"mstr_standard"
BODY_TYPE"PLUMBING"
HDL_TAP"TRUE";
"B \NAC \NWC"4;
"S \NAC"
BN"4"167;
%"TAP"
"1","(-7950,3575)","2","mstr_standard","I192";
;
CDS_LIB"mstr_standard"
BODY_TYPE"PLUMBING"
HDL_TAP"TRUE";
"B \NAC \NWC"4;
"S \NAC"
BN"5"168;
%"TAP"
"1","(-7950,3675)","2","mstr_standard","I193";
;
CDS_LIB"mstr_standard"
BODY_TYPE"PLUMBING"
HDL_TAP"TRUE";
"B \NAC \NWC"4;
"S \NAC"
BN"7"154;
%"TAP"
"1","(-7950,3625)","2","mstr_standard","I194";
;
CDS_LIB"mstr_standard"
BODY_TYPE"PLUMBING"
HDL_TAP"TRUE";
"B \NAC \NWC"4;
"S \NAC"
BN"6"135;
%"TAP"
"1","(-7950,3875)","2","mstr_standard","I195";
;
CDS_LIB"mstr_standard"
BODY_TYPE"PLUMBING"
HDL_TAP"TRUE";
"B \NAC \NWC"7;
"S \NAC"
BN"2"137;
%"TAP"
"1","(-7950,3825)","2","mstr_standard","I196";
;
CDS_LIB"mstr_standard"
BODY_TYPE"PLUMBING"
HDL_TAP"TRUE";
"B \NAC \NWC"7;
"S \NAC"
BN"1"155;
%"TAP"
"1","(-7950,3775)","2","mstr_standard","I197";
;
CDS_LIB"mstr_standard"
BODY_TYPE"PLUMBING"
HDL_TAP"TRUE";
"B \NAC \NWC"7;
"S \NAC"
BN"0"136;
%"TAP"
"1","(-7950,3925)","2","mstr_standard","I198";
;
CDS_LIB"mstr_standard"
BODY_TYPE"PLUMBING"
HDL_TAP"TRUE";
"B \NAC \NWC"7;
"S \NAC"
BN"3"138;
%"TAP"
"1","(-7950,3975)","2","mstr_standard","I199";
;
CDS_LIB"mstr_standard"
BODY_TYPE"PLUMBING"
HDL_TAP"TRUE";
"B \NAC \NWC"7;
"S \NAC"
BN"4"156;
%"TAP"
"1","(-7950,4025)","2","mstr_standard","I200";
;
CDS_LIB"mstr_standard"
BODY_TYPE"PLUMBING"
HDL_TAP"TRUE";
"B \NAC \NWC"7;
"S \NAC"
BN"5"139;
%"TAP"
"1","(-7950,4075)","2","mstr_standard","I201";
;
CDS_LIB"mstr_standard"
BODY_TYPE"PLUMBING"
HDL_TAP"TRUE";
"B \NAC \NWC"7;
"S \NAC"
BN"6"140;
%"TAP"
"1","(-7950,4125)","2","mstr_standard","I202";
;
CDS_LIB"mstr_standard"
BODY_TYPE"PLUMBING"
HDL_TAP"TRUE";
"B \NAC \NWC"7;
"S \NAC"
BN"7"157;
%"TAP"
"1","(-7950,4975)","2","mstr_standard","I203";
;
CDS_LIB"mstr_standard"
BODY_TYPE"PLUMBING"
HDL_TAP"TRUE";
"B \NAC \NWC"9;
"S \NAC"
BN"3"146;
%"TAP"
"1","(-7950,4875)","2","mstr_standard","I204";
;
CDS_LIB"mstr_standard"
BODY_TYPE"PLUMBING"
HDL_TAP"TRUE";
"B \NAC \NWC"9;
"S \NAC"
BN"1"150;
%"TAP"
"1","(-7950,4825)","2","mstr_standard","I205";
;
CDS_LIB"mstr_standard"
BODY_TYPE"PLUMBING"
HDL_TAP"TRUE";
"B \NAC \NWC"9;
"S \NAC"
BN"0"152;
%"TAP"
"1","(-7950,4925)","2","mstr_standard","I206";
;
CDS_LIB"mstr_standard"
BODY_TYPE"PLUMBING"
HDL_TAP"TRUE";
"B \NAC \NWC"9;
"S \NAC"
BN"2"148;
%"TAP"
"1","(-6250,2375)","0","mstr_standard","I207";
;
CDS_LIB"mstr_standard"
BODY_TYPE"PLUMBING"
HDL_TAP"TRUE";
"B \NAC \NWC"5;
"S \NAC"
BN"1"78;
%"TAP"
"1","(-6250,2325)","0","mstr_standard","I208";
;
CDS_LIB"mstr_standard"
BODY_TYPE"PLUMBING"
HDL_TAP"TRUE";
"B \NAC \NWC"5;
"S \NAC"
BN"0"77;
%"TAP"
"1","(-6250,2425)","0","mstr_standard","I209";
;
CDS_LIB"mstr_standard"
BODY_TYPE"PLUMBING"
HDL_TAP"TRUE";
"B \NAC \NWC"5;
"S \NAC"
BN"2"79;
%"TAP"
"1","(-6250,2475)","0","mstr_standard","I210";
;
CDS_LIB"mstr_standard"
BODY_TYPE"PLUMBING"
HDL_TAP"TRUE";
"B \NAC \NWC"5;
"S \NAC"
BN"3"80;
%"TAP"
"1","(-6250,2525)","0","mstr_standard","I211";
;
CDS_LIB"mstr_standard"
BODY_TYPE"PLUMBING"
HDL_TAP"TRUE";
"B \NAC \NWC"5;
"S \NAC"
BN"4"161;
%"TAP"
"1","(-6250,2575)","0","mstr_standard","I212";
;
CDS_LIB"mstr_standard"
BODY_TYPE"PLUMBING"
HDL_TAP"TRUE";
"B \NAC \NWC"5;
"S \NAC"
BN"5"81;
%"TAP"
"1","(-6250,2675)","0","mstr_standard","I213";
;
CDS_LIB"mstr_standard"
BODY_TYPE"PLUMBING"
HDL_TAP"TRUE";
"B \NAC \NWC"5;
"S \NAC"
BN"7"83;
%"TAP"
"1","(-6250,2625)","0","mstr_standard","I214";
;
CDS_LIB"mstr_standard"
BODY_TYPE"PLUMBING"
HDL_TAP"TRUE";
"B \NAC \NWC"5;
"S \NAC"
BN"6"82;
%"TAP"
"1","(-6250,2725)","0","mstr_standard","I215";
;
CDS_LIB"mstr_standard"
BODY_TYPE"PLUMBING"
HDL_TAP"TRUE";
"B \NAC \NWC"5;
"S \NAC"
BN"8"84;
%"TAP"
"1","(-6250,2775)","0","mstr_standard","I216";
;
CDS_LIB"mstr_standard"
BODY_TYPE"PLUMBING"
HDL_TAP"TRUE";
"B \NAC \NWC"5;
"S \NAC"
BN"9"85;
%"TAP"
"1","(-6250,2825)","0","mstr_standard","I217";
;
CDS_LIB"mstr_standard"
BODY_TYPE"PLUMBING"
HDL_TAP"TRUE";
"B \NAC \NWC"5;
"S \NAC"
BN"10"86;
%"TAP"
"1","(-6250,2875)","0","mstr_standard","I218";
;
CDS_LIB"mstr_standard"
BODY_TYPE"PLUMBING"
HDL_TAP"TRUE";
"B \NAC \NWC"5;
"S \NAC"
BN"11"87;
%"TAP"
"1","(-6250,2925)","0","mstr_standard","I219";
;
CDS_LIB"mstr_standard"
BODY_TYPE"PLUMBING"
HDL_TAP"TRUE";
"B \NAC \NWC"5;
"S \NAC"
BN"12"88;
%"TAP"
"1","(-6250,2975)","0","mstr_standard","I220";
;
CDS_LIB"mstr_standard"
BODY_TYPE"PLUMBING"
HDL_TAP"TRUE";
"B \NAC \NWC"5;
"S \NAC"
BN"13"89;
%"TAP"
"1","(-6250,3075)","0","mstr_standard","I221";
;
CDS_LIB"mstr_standard"
BODY_TYPE"PLUMBING"
HDL_TAP"TRUE";
"B \NAC \NWC"5;
"S \NAC"
BN"15"91;
%"TAP"
"1","(-6250,3025)","0","mstr_standard","I222";
;
CDS_LIB"mstr_standard"
BODY_TYPE"PLUMBING"
HDL_TAP"TRUE";
"B \NAC \NWC"5;
"S \NAC"
BN"14"90;
%"TAP"
"1","(-6250,3225)","0","mstr_standard","I223";
;
CDS_LIB"mstr_standard"
BODY_TYPE"PLUMBING"
HDL_TAP"TRUE";
"B \NAC \NWC"5;
"S \NAC"
BN"18"94;
%"TAP"
"1","(-6250,3175)","0","mstr_standard","I224";
;
CDS_LIB"mstr_standard"
BODY_TYPE"PLUMBING"
HDL_TAP"TRUE";
"B \NAC \NWC"5;
"S \NAC"
BN"17"93;
%"TAP"
"1","(-6250,3125)","0","mstr_standard","I225";
;
CDS_LIB"mstr_standard"
BODY_TYPE"PLUMBING"
HDL_TAP"TRUE";
"B \NAC \NWC"5;
"S \NAC"
BN"16"92;
%"TAP"
"1","(-6250,3375)","0","mstr_standard","I226";
;
CDS_LIB"mstr_standard"
BODY_TYPE"PLUMBING"
HDL_TAP"TRUE";
"B \NAC \NWC"5;
"S \NAC"
BN"21"97;
%"TAP"
"1","(-6250,3425)","0","mstr_standard","I227";
;
CDS_LIB"mstr_standard"
BODY_TYPE"PLUMBING"
HDL_TAP"TRUE";
"B \NAC \NWC"5;
"S \NAC"
BN"22"98;
%"TAP"
"1","(-6250,3325)","0","mstr_standard","I228";
;
CDS_LIB"mstr_standard"
BODY_TYPE"PLUMBING"
HDL_TAP"TRUE";
"B \NAC \NWC"5;
"S \NAC"
BN"20"96;
%"TAP"
"1","(-6250,3475)","0","mstr_standard","I229";
;
CDS_LIB"mstr_standard"
BODY_TYPE"PLUMBING"
HDL_TAP"TRUE";
"B \NAC \NWC"5;
"S \NAC"
BN"23"99;
%"TAP"
"1","(-6250,3275)","0","mstr_standard","I230";
;
CDS_LIB"mstr_standard"
BODY_TYPE"PLUMBING"
HDL_TAP"TRUE";
"B \NAC \NWC"5;
"S \NAC"
BN"19"95;
%"TAP"
"1","(-6250,3625)","0","mstr_standard","I231";
;
CDS_LIB"mstr_standard"
BODY_TYPE"PLUMBING"
HDL_TAP"TRUE";
"B \NAC \NWC"5;
"S \NAC"
BN"26"101;
%"TAP"
"1","(-6250,3675)","0","mstr_standard","I232";
;
CDS_LIB"mstr_standard"
BODY_TYPE"PLUMBING"
HDL_TAP"TRUE";
"B \NAC \NWC"5;
"S \NAC"
BN"27"102;
%"TAP"
"1","(-6250,3575)","0","mstr_standard","I233";
;
CDS_LIB"mstr_standard"
BODY_TYPE"PLUMBING"
HDL_TAP"TRUE";
"B \NAC \NWC"5;
"S \NAC"
BN"25"100;
%"TAP"
"1","(-6250,3725)","0","mstr_standard","I234";
;
CDS_LIB"mstr_standard"
BODY_TYPE"PLUMBING"
HDL_TAP"TRUE";
"B \NAC \NWC"5;
"S \NAC"
BN"28"103;
%"TAP"
"1","(-6250,3525)","0","mstr_standard","I235";
;
CDS_LIB"mstr_standard"
BODY_TYPE"PLUMBING"
HDL_TAP"TRUE";
"B \NAC \NWC"5;
"S \NAC"
BN"24"23;
%"TAP"
"1","(-6250,3975)","0","mstr_standard","I236";
;
CDS_LIB"mstr_standard"
BODY_TYPE"PLUMBING"
HDL_TAP"TRUE";
"B \NAC \NWC"6;
"S \NAC"
BN"0"106;
%"TAP"
"1","(-6250,3825)","0","mstr_standard","I237";
;
CDS_LIB"mstr_standard"
BODY_TYPE"PLUMBING"
HDL_TAP"TRUE";
"B \NAC \NWC"5;
"S \NAC"
BN"30"24;
%"TAP"
"1","(-6250,3875)","0","mstr_standard","I238";
;
CDS_LIB"mstr_standard"
BODY_TYPE"PLUMBING"
HDL_TAP"TRUE";
"B \NAC \NWC"5;
"S \NAC"
BN"31"105;
%"TAP"
"1","(-6250,3775)","0","mstr_standard","I239";
;
CDS_LIB"mstr_standard"
BODY_TYPE"PLUMBING"
HDL_TAP"TRUE";
"B \NAC \NWC"5;
"S \NAC"
BN"29"104;
%"TAP"
"1","(-6250,4075)","0","mstr_standard","I240";
;
CDS_LIB"mstr_standard"
BODY_TYPE"PLUMBING"
HDL_TAP"TRUE";
"B \NAC \NWC"6;
"S \NAC"
BN"2"108;
%"TAP"
"1","(-6250,4025)","0","mstr_standard","I241";
;
CDS_LIB"mstr_standard"
BODY_TYPE"PLUMBING"
HDL_TAP"TRUE";
"B \NAC \NWC"6;
"S \NAC"
BN"1"107;
%"TAP"
"1","(-6250,4125)","0","mstr_standard","I242";
;
CDS_LIB"mstr_standard"
BODY_TYPE"PLUMBING"
HDL_TAP"TRUE";
"B \NAC \NWC"6;
"S \NAC"
BN"3"109;
%"TAP"
"1","(-6250,4175)","0","mstr_standard","I243";
;
CDS_LIB"mstr_standard"
BODY_TYPE"PLUMBING"
HDL_TAP"TRUE";
"B \NAC \NWC"6;
"S \NAC"
BN"4"110;
%"TAP"
"1","(-6250,4225)","0","mstr_standard","I244";
;
CDS_LIB"mstr_standard"
BODY_TYPE"PLUMBING"
HDL_TAP"TRUE";
"B \NAC \NWC"6;
"S \NAC"
BN"5"111;
%"TAP"
"1","(-6250,4325)","0","mstr_standard","I245";
;
CDS_LIB"mstr_standard"
BODY_TYPE"PLUMBING"
HDL_TAP"TRUE";
"B \NAC \NWC"6;
"S \NAC"
BN"7"113;
%"TAP"
"1","(-6250,4275)","0","mstr_standard","I246";
;
CDS_LIB"mstr_standard"
BODY_TYPE"PLUMBING"
HDL_TAP"TRUE";
"B \NAC \NWC"6;
"S \NAC"
BN"6"112;
%"TAP"
"1","(-6250,4375)","0","mstr_standard","I247";
;
CDS_LIB"mstr_standard"
BODY_TYPE"PLUMBING"
HDL_TAP"TRUE";
"B \NAC \NWC"6;
"S \NAC"
BN"8"114;
%"TAP"
"1","(-6250,4425)","0","mstr_standard","I248";
;
CDS_LIB"mstr_standard"
BODY_TYPE"PLUMBING"
HDL_TAP"TRUE";
"B \NAC \NWC"6;
"S \NAC"
BN"9"115;
%"TAP"
"1","(-6250,4475)","0","mstr_standard","I249";
;
CDS_LIB"mstr_standard"
BODY_TYPE"PLUMBING"
HDL_TAP"TRUE";
"B \NAC \NWC"6;
"S \NAC"
BN"10"116;
%"TAP"
"1","(-6250,4675)","0","mstr_standard","I250";
;
CDS_LIB"mstr_standard"
BODY_TYPE"PLUMBING"
HDL_TAP"TRUE";
"B \NAC \NWC"6;
"S \NAC"
BN"14"120;
%"TAP"
"1","(-6250,4725)","0","mstr_standard","I251";
;
CDS_LIB"mstr_standard"
BODY_TYPE"PLUMBING"
HDL_TAP"TRUE";
"B \NAC \NWC"6;
"S \NAC"
BN"15"121;
%"TAP"
"1","(-6250,4625)","0","mstr_standard","I252";
;
CDS_LIB"mstr_standard"
BODY_TYPE"PLUMBING"
HDL_TAP"TRUE";
"B \NAC \NWC"6;
"S \NAC"
BN"13"119;
%"TAP"
"1","(-6250,4575)","0","mstr_standard","I253";
;
CDS_LIB"mstr_standard"
BODY_TYPE"PLUMBING"
HDL_TAP"TRUE";
"B \NAC \NWC"6;
"S \NAC"
BN"12"118;
%"TAP"
"1","(-6250,4525)","0","mstr_standard","I254";
;
CDS_LIB"mstr_standard"
BODY_TYPE"PLUMBING"
HDL_TAP"TRUE";
"B \NAC \NWC"6;
"S \NAC"
BN"11"117;
%"TAP"
"1","(-6250,4825)","0","mstr_standard","I255";
;
CDS_LIB"mstr_standard"
BODY_TYPE"PLUMBING"
HDL_TAP"TRUE";
"B \NAC \NWC"6;
"S \NAC"
BN"17"123;
%"TAP"
"1","(-6250,4875)","0","mstr_standard","I256";
;
CDS_LIB"mstr_standard"
BODY_TYPE"PLUMBING"
HDL_TAP"TRUE";
"B \NAC \NWC"6;
"S \NAC"
BN"18"75;
%"TAP"
"1","(-6250,4775)","0","mstr_standard","I257";
;
CDS_LIB"mstr_standard"
BODY_TYPE"PLUMBING"
HDL_TAP"TRUE";
"B \NAC \NWC"6;
"S \NAC"
BN"16"122;
%"TAP"
"1","(-6250,4975)","0","mstr_standard","I258";
;
CDS_LIB"mstr_standard"
BODY_TYPE"PLUMBING"
HDL_TAP"TRUE";
"B \NAC \NWC"6;
"S \NAC"
BN"20"124;
%"TAP"
"1","(-6250,4925)","0","mstr_standard","I259";
;
CDS_LIB"mstr_standard"
BODY_TYPE"PLUMBING"
HDL_TAP"TRUE";
"B \NAC \NWC"6;
"S \NAC"
BN"19"74;
%"TAP"
"1","(-7950,5125)","2","mstr_standard","I263";
;
CDS_LIB"mstr_standard"
BODY_TYPE"PLUMBING"
HDL_TAP"TRUE";
"B \NAC \NWC"9;
"S \NAC"
BN"6"141;
%"TAP"
"1","(-7950,5025)","2","mstr_standard","I264";
;
CDS_LIB"mstr_standard"
BODY_TYPE"PLUMBING"
HDL_TAP"TRUE";
"B \NAC \NWC"9;
"S \NAC"
BN"4"144;
%"TAP"
"1","(-7950,5075)","2","mstr_standard","I265";
;
CDS_LIB"mstr_standard"
BODY_TYPE"PLUMBING"
HDL_TAP"TRUE";
"B \NAC \NWC"9;
"S \NAC"
BN"5"142;
%"TAP"
"1","(-7950,5225)","2","mstr_standard","I266";
;
CDS_LIB"mstr_standard"
BODY_TYPE"PLUMBING"
HDL_TAP"TRUE";
"B \NAC \NWC"8;
"S \NAC"
BN"0"153;
%"TAP"
"1","(-7950,5275)","2","mstr_standard","I267";
;
CDS_LIB"mstr_standard"
BODY_TYPE"PLUMBING"
HDL_TAP"TRUE";
"B \NAC \NWC"8;
"S \NAC"
BN"1"151;
%"TAP"
"1","(-7950,5325)","2","mstr_standard","I268";
;
CDS_LIB"mstr_standard"
BODY_TYPE"PLUMBING"
HDL_TAP"TRUE";
"B \NAC \NWC"8;
"S \NAC"
BN"2"149;
%"TAP"
"1","(-7950,5375)","2","mstr_standard","I269";
;
CDS_LIB"mstr_standard"
BODY_TYPE"PLUMBING"
HDL_TAP"TRUE";
"B \NAC \NWC"8;
"S \NAC"
BN"3"147;
%"TAP"
"1","(-7950,5475)","2","mstr_standard","I270";
;
CDS_LIB"mstr_standard"
BODY_TYPE"PLUMBING"
HDL_TAP"TRUE";
"B \NAC \NWC"8;
"S \NAC"
BN"5"143;
%"TAP"
"1","(-7950,5425)","2","mstr_standard","I271";
;
CDS_LIB"mstr_standard"
BODY_TYPE"PLUMBING"
HDL_TAP"TRUE";
"B \NAC \NWC"8;
"S \NAC"
BN"4"145;
%"TAP"
"1","(-7950,5525)","2","mstr_standard","I272";
;
CDS_LIB"mstr_standard"
BODY_TYPE"PLUMBING"
HDL_TAP"TRUE";
"B \NAC \NWC"8;
"S \NAC"
BN"6"73;
%"TAP"
"1","(-6250,5125)","0","mstr_standard","I273";
;
CDS_LIB"mstr_standard"
BODY_TYPE"PLUMBING"
HDL_TAP"TRUE";
"B \NAC \NWC"6;
"S \NAC"
BN"23"127;
%"TAP"
"1","(-6250,5025)","0","mstr_standard","I274";
;
CDS_LIB"mstr_standard"
BODY_TYPE"PLUMBING"
HDL_TAP"TRUE";
"B \NAC \NWC"6;
"S \NAC"
BN"21"125;
%"TAP"
"1","(-6250,5075)","0","mstr_standard","I275";
;
CDS_LIB"mstr_standard"
BODY_TYPE"PLUMBING"
HDL_TAP"TRUE";
"B \NAC \NWC"6;
"S \NAC"
BN"22"126;
%"TAP"
"1","(-6250,5175)","0","mstr_standard","I276";
;
CDS_LIB"mstr_standard"
BODY_TYPE"PLUMBING"
HDL_TAP"TRUE";
"B \NAC \NWC"6;
"S \NAC"
BN"24"128;
%"TAP"
"1","(-6250,5225)","0","mstr_standard","I277";
;
CDS_LIB"mstr_standard"
BODY_TYPE"PLUMBING"
HDL_TAP"TRUE";
"B \NAC \NWC"6;
"S \NAC"
BN"25"30;
%"TAP"
"1","(-6250,5275)","0","mstr_standard","I278";
;
CDS_LIB"mstr_standard"
BODY_TYPE"PLUMBING"
HDL_TAP"TRUE";
"B \NAC \NWC"6;
"S \NAC"
BN"26"29;
%"TAP"
"1","(-6250,5525)","0","mstr_standard","I279";
;
CDS_LIB"mstr_standard"
BODY_TYPE"PLUMBING"
HDL_TAP"TRUE";
"B \NAC \NWC"6;
"S \NAC"
BN"31"158;
%"TAP"
"1","(-6250,5325)","0","mstr_standard","I280";
;
CDS_LIB"mstr_standard"
BODY_TYPE"PLUMBING"
HDL_TAP"TRUE";
"B \NAC \NWC"6;
"S \NAC"
BN"27"71;
%"TAP"
"1","(-6250,5375)","0","mstr_standard","I281";
;
CDS_LIB"mstr_standard"
BODY_TYPE"PLUMBING"
HDL_TAP"TRUE";
"B \NAC \NWC"6;
"S \NAC"
BN"28"72;
%"TAP"
"1","(-6250,5475)","0","mstr_standard","I282";
;
CDS_LIB"mstr_standard"
BODY_TYPE"PLUMBING"
HDL_TAP"TRUE";
"B \NAC \NWC"6;
"S \NAC"
BN"30"130;
%"TAP"
"1","(-6250,5425)","0","mstr_standard","I283";
;
CDS_LIB"mstr_standard"
BODY_TYPE"PLUMBING"
HDL_TAP"TRUE";
"B \NAC \NWC"6;
"S \NAC"
BN"29"129;
%"TAP"
"1","(-3650,2700)","0","mstr_standard","I285";
;
CDS_LIB"mstr_standard"
BODY_TYPE"PLUMBING"
HDL_TAP"TRUE";
"B \NAC \NWC"12;
"S \NAC"
BN"0"64;
%"TAP"
"1","(-3650,2800)","0","mstr_standard","I286";
;
CDS_LIB"mstr_standard"
BODY_TYPE"PLUMBING"
HDL_TAP"TRUE";
"B \NAC \NWC"12;
"S \NAC"
BN"1"60;
%"TAP"
"1","(-3450,2850)","0","mstr_standard","I287";
;
CDS_LIB"mstr_standard"
BODY_TYPE"PLUMBING"
HDL_TAP"TRUE";
"B \NAC \NWC"13;
"S \NAC"
BN"2"57;
%"TAP"
"1","(-3450,2750)","0","mstr_standard","I288";
;
CDS_LIB"mstr_standard"
BODY_TYPE"PLUMBING"
HDL_TAP"TRUE";
"B \NAC \NWC"13;
"S \NAC"
BN"1"61;
%"TAP"
"1","(-3450,2650)","0","mstr_standard","I289";
;
CDS_LIB"mstr_standard"
BODY_TYPE"PLUMBING"
HDL_TAP"TRUE";
"B \NAC \NWC"13;
"S \NAC"
BN"0"65;
%"TAP"
"1","(-3650,2900)","0","mstr_standard","I290";
;
CDS_LIB"mstr_standard"
BODY_TYPE"PLUMBING"
HDL_TAP"TRUE";
"B \NAC \NWC"12;
"S \NAC"
BN"2"56;
%"TAP"
"1","(-3650,3000)","0","mstr_standard","I291";
;
CDS_LIB"mstr_standard"
BODY_TYPE"PLUMBING"
HDL_TAP"TRUE";
"B \NAC \NWC"12;
"S \NAC"
BN"3"52;
%"TAP"
"1","(-3650,3100)","0","mstr_standard","I292";
;
CDS_LIB"mstr_standard"
BODY_TYPE"PLUMBING"
HDL_TAP"TRUE";
"B \NAC \NWC"12;
"S \NAC"
BN"4"48;
%"TAP"
"1","(-3450,2950)","0","mstr_standard","I293";
;
CDS_LIB"mstr_standard"
BODY_TYPE"PLUMBING"
HDL_TAP"TRUE";
"B \NAC \NWC"13;
"S \NAC"
BN"3"53;
%"TAP"
"1","(-3450,3050)","0","mstr_standard","I294";
;
CDS_LIB"mstr_standard"
BODY_TYPE"PLUMBING"
HDL_TAP"TRUE";
"B \NAC \NWC"13;
"S \NAC"
BN"4"49;
%"TAP"
"1","(-3650,3200)","0","mstr_standard","I295";
;
CDS_LIB"mstr_standard"
BODY_TYPE"PLUMBING"
HDL_TAP"TRUE";
"B \NAC \NWC"12;
"S \NAC"
BN"5"44;
%"TAP"
"1","(-3650,3300)","0","mstr_standard","I296";
;
CDS_LIB"mstr_standard"
BODY_TYPE"PLUMBING"
HDL_TAP"TRUE";
"B \NAC \NWC"12;
"S \NAC"
BN"6"41;
%"TAP"
"1","(-3450,3350)","0","mstr_standard","I297";
;
CDS_LIB"mstr_standard"
BODY_TYPE"PLUMBING"
HDL_TAP"TRUE";
"B \NAC \NWC"13;
"S \NAC"
BN"7"39;
%"TAP"
"1","(-3450,3250)","0","mstr_standard","I298";
;
CDS_LIB"mstr_standard"
BODY_TYPE"PLUMBING"
HDL_TAP"TRUE";
"B \NAC \NWC"13;
"S \NAC"
BN"6"42;
%"TAP"
"1","(-3450,3150)","0","mstr_standard","I299";
;
CDS_LIB"mstr_standard"
BODY_TYPE"PLUMBING"
HDL_TAP"TRUE";
"B \NAC \NWC"13;
"S \NAC"
BN"5"45;
%"TAP"
"1","(-3650,3400)","0","mstr_standard","I300";
;
CDS_LIB"mstr_standard"
BODY_TYPE"PLUMBING"
HDL_TAP"TRUE";
"B \NAC \NWC"12;
"S \NAC"
BN"7"66;
%"TAP"
"1","(-3650,3500)","0","mstr_standard","I301";
;
CDS_LIB"mstr_standard"
BODY_TYPE"PLUMBING"
HDL_TAP"TRUE";
"B \NAC \NWC"12;
"S \NAC"
BN"8"68;
%"TAP"
"1","(-3650,3600)","0","mstr_standard","I302";
;
CDS_LIB"mstr_standard"
BODY_TYPE"PLUMBING"
HDL_TAP"TRUE";
"B \NAC \NWC"12;
"S \NAC"
BN"9"31;
%"TAP"
"1","(-3450,3450)","0","mstr_standard","I303";
;
CDS_LIB"mstr_standard"
BODY_TYPE"PLUMBING"
HDL_TAP"TRUE";
"B \NAC \NWC"13;
"S \NAC"
BN"8"67;
%"TAP"
"1","(-3450,3550)","0","mstr_standard","I304";
;
CDS_LIB"mstr_standard"
BODY_TYPE"PLUMBING"
HDL_TAP"TRUE";
"B \NAC \NWC"13;
"S \NAC"
BN"9"32;
%"TAP"
"1","(-3650,3750)","0","mstr_standard","I305";
;
CDS_LIB"mstr_standard"
BODY_TYPE"PLUMBING"
HDL_TAP"TRUE";
"B \NAC \NWC"11;
"S \NAC"
BN"0"34;
%"TAP"
"1","(-3650,3850)","0","mstr_standard","I306";
;
CDS_LIB"mstr_standard"
BODY_TYPE"PLUMBING"
HDL_TAP"TRUE";
"B \NAC \NWC"11;
"S \NAC"
BN"1"62;
%"TAP"
"1","(-3450,3700)","0","mstr_standard","I307";
;
CDS_LIB"mstr_standard"
BODY_TYPE"PLUMBING"
HDL_TAP"TRUE";
"B \NAC \NWC"10;
"S \NAC"
BN"0"33;
%"TAP"
"1","(-3450,3800)","0","mstr_standard","I308";
;
CDS_LIB"mstr_standard"
BODY_TYPE"PLUMBING"
HDL_TAP"TRUE";
"B \NAC \NWC"10;
"S \NAC"
BN"1"63;
%"TAP"
"1","(-3650,3950)","0","mstr_standard","I309";
;
CDS_LIB"mstr_standard"
BODY_TYPE"PLUMBING"
HDL_TAP"TRUE";
"B \NAC \NWC"11;
"S \NAC"
BN"2"58;
%"TAP"
"1","(-3650,4050)","0","mstr_standard","I310";
;
CDS_LIB"mstr_standard"
BODY_TYPE"PLUMBING"
HDL_TAP"TRUE";
"B \NAC \NWC"11;
"S \NAC"
BN"3"54;
%"TAP"
"1","(-3450,3900)","0","mstr_standard","I311";
;
CDS_LIB"mstr_standard"
BODY_TYPE"PLUMBING"
HDL_TAP"TRUE";
"B \NAC \NWC"10;
"S \NAC"
BN"2"59;
%"TAP"
"1","(-3450,4000)","0","mstr_standard","I312";
;
CDS_LIB"mstr_standard"
BODY_TYPE"PLUMBING"
HDL_TAP"TRUE";
"B \NAC \NWC"10;
"S \NAC"
BN"3"55;
%"TAP"
"1","(-3450,4100)","0","mstr_standard","I313";
;
CDS_LIB"mstr_standard"
BODY_TYPE"PLUMBING"
HDL_TAP"TRUE";
"B \NAC \NWC"10;
"S \NAC"
BN"4"51;
%"TAP"
"1","(-3650,4150)","0","mstr_standard","I316";
;
CDS_LIB"mstr_standard"
BODY_TYPE"PLUMBING"
HDL_TAP"TRUE";
"B \NAC \NWC"11;
"S \NAC"
BN"4"50;
%"TAP"
"1","(-3650,4250)","0","mstr_standard","I317";
;
CDS_LIB"mstr_standard"
BODY_TYPE"PLUMBING"
HDL_TAP"TRUE";
"B \NAC \NWC"11;
"S \NAC"
BN"5"46;
%"TAP"
"1","(-3650,4350)","0","mstr_standard","I318";
;
CDS_LIB"mstr_standard"
BODY_TYPE"PLUMBING"
HDL_TAP"TRUE";
"B \NAC \NWC"11;
"S \NAC"
BN"6"69;
%"TAP"
"1","(-3450,4400)","0","mstr_standard","I319";
;
CDS_LIB"mstr_standard"
BODY_TYPE"PLUMBING"
HDL_TAP"TRUE";
"B \NAC \NWC"10;
"S \NAC"
BN"7"70;
%"TAP"
"1","(-3450,4300)","0","mstr_standard","I320";
;
CDS_LIB"mstr_standard"
BODY_TYPE"PLUMBING"
HDL_TAP"TRUE";
"B \NAC \NWC"10;
"S \NAC"
BN"6"43;
%"TAP"
"1","(-3450,4200)","0","mstr_standard","I321";
;
CDS_LIB"mstr_standard"
BODY_TYPE"PLUMBING"
HDL_TAP"TRUE";
"B \NAC \NWC"10;
"S \NAC"
BN"5"47;
%"TAP"
"1","(-3650,4450)","0","mstr_standard","I322";
;
CDS_LIB"mstr_standard"
BODY_TYPE"PLUMBING"
HDL_TAP"TRUE";
"B \NAC \NWC"11;
"S \NAC"
BN"7"40;
%"TAP"
"1","(-3650,4550)","0","mstr_standard","I323";
;
CDS_LIB"mstr_standard"
BODY_TYPE"PLUMBING"
HDL_TAP"TRUE";
"B \NAC \NWC"11;
"S \NAC"
BN"8"37;
%"TAP"
"1","(-3650,4650)","0","mstr_standard","I324";
;
CDS_LIB"mstr_standard"
BODY_TYPE"PLUMBING"
HDL_TAP"TRUE";
"B \NAC \NWC"11;
"S \NAC"
BN"9"35;
%"TAP"
"1","(-3450,4600)","0","mstr_standard","I325";
;
CDS_LIB"mstr_standard"
BODY_TYPE"PLUMBING"
HDL_TAP"TRUE";
"B \NAC \NWC"10;
"S \NAC"
BN"9"36;
%"TAP"
"1","(-3450,4500)","0","mstr_standard","I326";
;
CDS_LIB"mstr_standard"
BODY_TYPE"PLUMBING"
HDL_TAP"TRUE";
"B \NAC \NWC"10;
"S \NAC"
BN"8"38;
%"GND"
"1","(-6650,1175)","0","mstr_symbols","I332";
;
VOLTAGE"0.0"
SIZE"1B"
CDS_LIB"mstr_symbols"
BOM_COST"MEM"
BODY_TYPE"PLUMBING"
HDL_POWER"GND";
"A\NAC"1;
%"Q_RES"
"2","(-6650,1400)","0","pure_quanta","I349";
;
LOCATION"R761"
$SEC"1"
CDS_SEC"1"
PACK_TYPE"0402LF"
VALUE"15.4K"
TOLERANCE"1%"
MATERIAL"CHIP"
WATTAGE"1/16W"
CDS_LIB"pure_quanta"
PART_NUMBER"CS31542FB02";
"A"
$PN"1"159;
"B"
$PN"2"1;
%"SCONN288_DDR506112002KQ"
"1","(-7100,3775)","0","pure_quanta","I350";
;
LOCATION"J15"
$SEC"1"
CDS_SEC"1"
MATERIAL"IO"
VALUE"SCONN288_DDR506112002KQ"
PART_TYPE"SMLF"
CDS_LIB"pure_quanta"
NEEDS_NO_SIZE"TRUE"
CDS_LMAN_SYM_OUTLINE"-450,1900,450,-1850"
PART_NUMBER"DFHST8FS479";
"PWR_GOOD||FAIL_N"
$PN"147"17;
"DQ31_A"
$PN"194"158;
"CB7_A"
$PN"205"157;
"CB4_A"
$PN"58"156;
"CB1_A"
$PN"53"155;
"CB7_B"
$PN"236"154;
"ALERT_N \B"
$PN"62"172;
"CA0_A"
$PN"66"153;
"CA0_B"
$PN"76"152;
"CA1_A"
$PN"211"151;
"CA1_B"
$PN"221"150;
"CA2_A"
$PN"68"149;
"CA2_B"
$PN"78"148;
"CA3_A"
$PN"213"147;
"CA3_B"
$PN"223"146;
"CA4_A"
$PN"70"145;
"CA4_B"
$PN"80"144;
"CA5_A"
$PN"215"143;
"CA5_B"
$PN"225"142;
"CA6_A"
$PN"72"73;
"CA6_B"
$PN"82"141;
"CB6_A"
$PN"203"140;
"CB5_A"
$PN"60"139;
"CB3_A"
$PN"198"138;
"CB2_A"
$PN"196"137;
"CB0_A"
$PN"51"136;
"CB6_B"
$PN"234"135;
"CB5_B"
$PN"91"168;
"CB4_B"
$PN"89"167;
"CB3_B"
$PN"243"19;
"CB2_B"
$PN"241"22;
"CB1_B"
$PN"98"21;
"CB0_B"
$PN"96"20;
"CK_C \B"
$PN"218"134;
"CK_T"
$PN"217"25;
"CS0_A_N"
$PN"64"133;
"CS0_B_N"
$PN"84"26;
"CS1_A_N"
$PN"209"132;
"CS1_B_N"
$PN"229"131;
"DQ30_A"
$PN"192"130;
"DQ29_A"
$PN"49"129;
"DQ28_A"
$PN"47"72;
"DQ27_A"
$PN"187"71;
"DQ26_A"
$PN"185"29;
"DQ25_A"
$PN"42"30;
"DQ24_A"
$PN"40"128;
"DQ23_A"
$PN"183"127;
"DQ22_A"
$PN"181"126;
"DQ21_A"
$PN"38"125;
"DQ20_A"
$PN"36"124;
"DQ19_A"
$PN"176"74;
"DQ18_A"
$PN"174"75;
"DQ17_A"
$PN"31"123;
"DQ16_A"
$PN"29"122;
"DQ15_A"
$PN"172"121;
"DQ14_A"
$PN"170"120;
"DQ13_A"
$PN"27"119;
"DQ12_A"
$PN"25"118;
"DQ11_A"
$PN"165"117;
"DQ10_A"
$PN"163"116;
"DQ9_A"
$PN"20"115;
"DQ8_A"
$PN"18"114;
"DQ7_A"
$PN"161"113;
"DQ6_A"
$PN"159"112;
"DQ5_A"
$PN"16"111;
"DQ4_A"
$PN"14"110;
"DQ3_A"
$PN"154"109;
"DQ2_A"
$PN"152"108;
"DQ1_A"
$PN"9"107;
"DQ0_A"
$PN"7"106;
"DQ31_B"
$PN"287"105;
"DQ30_B"
$PN"285"24;
"DQ29_B"
$PN"142"104;
"DQ28_B"
$PN"140"103;
"DQ27_B"
$PN"280"102;
"DQ26_B"
$PN"278"101;
"DQ25_B"
$PN"135"100;
"DQ24_B"
$PN"133"23;
"DQ23_B"
$PN"276"99;
"DQ22_B"
$PN"274"98;
"DQ21_B"
$PN"131"97;
"DQ20_B"
$PN"129"96;
"DQ19_B"
$PN"269"95;
"DQ18_B"
$PN"267"94;
"DQ17_B"
$PN"124"93;
"DQ16_B"
$PN"122"92;
"DQ15_B"
$PN"265"91;
"DQ14_B"
$PN"263"90;
"DQ13_B"
$PN"120"89;
"DQ12_B"
$PN"118"88;
"DQ11_B"
$PN"258"87;
"DQ10_B"
$PN"256"86;
"DQ9_B"
$PN"113"85;
"DQ8_B"
$PN"111"84;
"DQ7_B"
$PN"254"83;
"DQ6_B"
$PN"252"82;
"DQ5_B"
$PN"109"81;
"DQ4_B"
$PN"107"161;
"DQ3_B"
$PN"247"80;
"DQ2_B"
$PN"245"79;
"DQ1_B"
$PN"102"78;
"DQ0_B"
$PN"100"77;
"HAS"
$PN"148"18;
"HSCL"
$PN"4"169;
"HSDA"
$PN"5"15;
"LBD||RSP_A_N"
$PN"86"76;
"LBS||RSP_B_N"
$PN"87"160;
"PAR_A"
$PN"74"27;
"PAR_B"
$PN"227"28;
"RESET_N \B"
$PN"207"171;
"RFU6"
$PN"232"0;
"RFU5"
$PN"231"0;
"RFU4"
$PN"220"0;
"RFU3"
$PN"150"0;
"RFU2"
$PN"149"0;
"RFU1"
$PN"144"0;
"RFU0"
$PN"2"0;
"VIN_MGMT"
$PN"3"14;
%"SCONN288_DDR506112002KQ"
"3","(-1225,3575)","0","pure_quanta","I352";
;
LOCATION"J15"
$SEC"3"
CDS_SEC"3"
PART_TYPE"SMLF"
MATERIAL"IO"
VALUE"SCONN288_DDR506112002KQ"
CDS_LIB"pure_quanta"
NEEDS_NO_SIZE"TRUE"
CDS_LMAN_SYM_OUTLINE"-450,1800,450,-1750"
PART_NUMBER"DFHST8FS479";
"G3"
$PN"G3"164;
"G2"
$PN"G2"164;
"G1"
$PN"G1"164;
"VSS62"
$PN"141"164;
"VSS61"
$PN"139"164;
"VSS60"
$PN"136"164;
"VSS58"
$PN"132"164;
"VSS104"
$PN"240"163;
"VSS102"
$PN"235"163;
"VSS100"
$PN"230"163;
"VIN_BULK2"
$PN"146"166;
"VIN_BULK1"
$PN"145"166;
"VIN_BULK0"
$PN"1"166;
"VSS126"
$PN"288"163;
"VSS125"
$PN"286"163;
"VSS124"
$PN"284"163;
"VSS123"
$PN"281"163;
"VSS122"
$PN"279"163;
"VSS121"
$PN"277"163;
"VSS120"
$PN"275"163;
"VSS119"
$PN"273"163;
"VSS118"
$PN"270"163;
"VSS117"
$PN"268"163;
"VSS116"
$PN"266"163;
"VSS115"
$PN"264"163;
"VSS114"
$PN"262"163;
"VSS113"
$PN"259"163;
"VSS112"
$PN"257"163;
"VSS111"
$PN"255"163;
"VSS110"
$PN"253"163;
"VSS109"
$PN"251"163;
"VSS108"
$PN"248"163;
"VSS107"
$PN"246"163;
"VSS106"
$PN"244"163;
"VSS105"
$PN"242"163;
"VSS103"
$PN"237"163;
"VSS101"
$PN"233"163;
"VSS99"
$PN"228"163;
"VSS98"
$PN"226"163;
"VSS97"
$PN"224"163;
"VSS96"
$PN"222"163;
"VSS95"
$PN"219"163;
"VSS94"
$PN"216"163;
"VSS93"
$PN"214"163;
"VSS92"
$PN"212"163;
"VSS91"
$PN"210"163;
"VSS90"
$PN"208"163;
"VSS89"
$PN"206"163;
"VSS88"
$PN"204"163;
"VSS87"
$PN"202"163;
"VSS86"
$PN"199"163;
"VSS85"
$PN"197"163;
"VSS84"
$PN"195"163;
"VSS83"
$PN"193"163;
"VSS82"
$PN"191"163;
"VSS81"
$PN"188"163;
"VSS80"
$PN"186"163;
"VSS79"
$PN"184"163;
"VSS78"
$PN"182"163;
"VSS77"
$PN"180"163;
"VSS76"
$PN"177"163;
"VSS75"
$PN"175"163;
"VSS74"
$PN"173"163;
"VSS73"
$PN"171"163;
"VSS72"
$PN"169"163;
"VSS71"
$PN"166"163;
"VSS70"
$PN"164"163;
"VSS69"
$PN"162"163;
"VSS68"
$PN"160"163;
"VSS67"
$PN"158"163;
"VSS66"
$PN"155"163;
"VSS65"
$PN"153"163;
"VSS64"
$PN"151"163;
"VSS63"
$PN"143"164;
"VSS59"
$PN"134"164;
"VSS57"
$PN"130"164;
"VSS56"
$PN"128"164;
"VSS55"
$PN"125"164;
"VSS54"
$PN"123"164;
"VSS53"
$PN"121"164;
"VSS52"
$PN"119"164;
"VSS51"
$PN"117"164;
"VSS50"
$PN"114"164;
"VSS49"
$PN"112"164;
"VSS48"
$PN"110"164;
"VSS47"
$PN"108"164;
"VSS46"
$PN"106"164;
"VSS45"
$PN"103"164;
"VSS44"
$PN"101"164;
"VSS43"
$PN"99"164;
"VSS42"
$PN"97"164;
"VSS41"
$PN"95"164;
"VSS40"
$PN"92"164;
"VSS39"
$PN"90"164;
"VSS38"
$PN"88"164;
"VSS37"
$PN"85"164;
"VSS36"
$PN"83"164;
"VSS35"
$PN"81"164;
"VSS34"
$PN"79"164;
"VSS33"
$PN"77"164;
"VSS32"
$PN"75"164;
"VSS31"
$PN"73"164;
"VSS30"
$PN"71"164;
"VSS29"
$PN"69"164;
"VSS28"
$PN"67"164;
"VSS27"
$PN"65"164;
"VSS26"
$PN"63"164;
"VSS25"
$PN"61"164;
"VSS24"
$PN"59"164;
"VSS23"
$PN"57"164;
"VSS22"
$PN"54"164;
"VSS21"
$PN"52"164;
"VSS20"
$PN"50"164;
"VSS19"
$PN"48"164;
"VSS18"
$PN"46"164;
"VSS17"
$PN"43"164;
"VSS16"
$PN"41"164;
"VSS15"
$PN"39"164;
"VSS14"
$PN"37"164;
"VSS13"
$PN"35"164;
"VSS12"
$PN"32"164;
"VSS11"
$PN"30"164;
"VSS10"
$PN"28"164;
"VSS9"
$PN"26"164;
"VSS8"
$PN"24"164;
"VSS7"
$PN"21"164;
"VSS6"
$PN"19"164;
"VSS5"
$PN"17"164;
"VSS4"
$PN"15"164;
"VSS3"
$PN"13"164;
"VSS2"
$PN"10"164;
"VSS1"
$PN"8"164;
"VSS0"
$PN"6"164;
%"GND"
"1","(-9050,3100)","0","mstr_symbols","I361";
;
ROOM"MEM_EFGH_DECOUPLING_CAPS"
VOLTAGE"0"
CDS_LIB"mstr_symbols"
SIZE"1B"
BOM_COST"MEM"
BODY_TYPE"PLUMBING"
HDL_POWER"GND";
"A\NAC"2;
%"Q_CAP"
"1","(-9050,3325)","2","pure_quanta","I362";
;
LOCATION"C92"
$SEC"1"
CDS_SEC"1"
TOLERANCE"10%"
VOLTAGE"25V"
PACK_TYPE"0402"
MATERIAL"X7R"
VALUE"0.1UF"
BOM_COST"MEM"
CDS_LIB"pure_quanta"
ROOM""
PART_NUMBER"CH4104K1B00";
"B"
$PN"2"2;
"A"
$PN"1"14;
%"Q_RES"
"1","(-8675,2275)","2","pure_quanta","I364";
;
LOCATION"R292"
$SEC"1"
CDS_SEC"1"
VALUE"1K"
PACK_TYPE"0402LF"
MATERIAL"CHIP"
WATTAGE"1/16W"
CDS_LIB"pure_quanta"
BOM_COST"MEM"
TOLERANCE"1%"
ROOM""
PART_NUMBER"CS21002FB06";
"B"
$PN"2"162;
"A"
$PN"1"17;
%"Q_RES"
"2","(-8550,2425)","0","pure_quanta","I365";
;
LOCATION"R90"
$SEC"1"
CDS_SEC"1"
WATTAGE"1/16W"
PACK_TYPE"0402LF"
VALUE"1K"
MATERIAL"EMPTY"
TOLERANCE"1%"
BOM_COST"MEM"
CDS_LIB"pure_quanta"
ROOM""
PART_NUMBER"CS21002FB06";
"A"
$PN"1"3;
"B"
$PN"2"17;
%"VCC_CORE"
"1","(-8550,2600)","0","mstr_symbols","I366";
;
HDL_POWER"P3V3"
ROOM"PVCCINFAON_CPU0_CTRL"
VOLTAGE"3.3"
CDS_LIB"mstr_symbols";
"A"3;
%"SCONN288_DDR506112002KQ"
"2","(-4600,3650)","0","pure_quanta","I367";
;
LOCATION"J15"
$SEC"2"
CDS_SEC"2"
PART_TYPE"SMLF"
VALUE"SCONN288_DDR506112002KQ"
MATERIAL"IO"
CDS_LIB"pure_quanta"
NEEDS_NO_SIZE"TRUE"
CDS_LMAN_SYM_OUTLINE"-600,1150,600,-1150"
PART_NUMBER"DFHST8FS479";
"DQS7_A_C||TDQS7_A_C \B"
$PN"178"70;
"DQS6_A_T||TDQS6_A_T"
$PN"168"69;
"DQS8_B_T||TDQS8_B_T"
$PN"283"68;
"DQS8_B_C||TDQS8_B_C \B"
$PN"282"67;
"DQS7_B_T||TDQS7_B_T"
$PN"272"66;
"DQS0_A_C \B"
$PN"12"33;
"DQS0_A_T"
$PN"11"34;
"DQS0_B_C \B"
$PN"105"65;
"DQS0_B_T"
$PN"104"64;
"DQS1_A_C \B"
$PN"23"63;
"DQS1_A_T"
$PN"22"62;
"DQS1_B_C \B"
$PN"116"61;
"DQS1_B_T"
$PN"115"60;
"DQS2_A_C \B"
$PN"34"59;
"DQS2_A_T"
$PN"33"58;
"DQS2_B_C \B"
$PN"127"57;
"DQS2_B_T"
$PN"126"56;
"DQS3_A_C \B"
$PN"45"55;
"DQS3_A_T"
$PN"44"54;
"DQS3_B_C \B"
$PN"138"53;
"DQS3_B_T"
$PN"137"52;
"DQS4_A_C \B"
$PN"56"51;
"DQS4_A_T"
$PN"55"50;
"DQS4_B_C \B"
$PN"238"49;
"DQS4_B_T"
$PN"239"48;
"DQS5_A_C||TDQS5_A_C||DQS5_A_T||TDQS5_A_T \B"
$PN"156"47;
"DQS5_A_T||TDQS5_A_T"
$PN"157"46;
"DQS5_B_C||TDQS5_B_C \B"
$PN"249"45;
"DQS5_B_T||TDQS5_B_T"
$PN"250"44;
"DQS6_A_C||TDQS6_A_C||DQS6_A_T||TDQS6_A_T \B"
$PN"167"43;
"DQS6_B_C||TDQS6_B_C \B"
$PN"260"42;
"DQS6_B_T||TDQS6_B_T"
$PN"261"41;
"DQS7_A_T||TDQS7_A_T"
$PN"179"40;
"DQS7_B_C||TDQS7_B_C \B"
$PN"271"39;
"DQS8_A_C||TDQS8_A_C \B"
$PN"189"38;
"DQS8_A_T||TDQS8_A_T"
$PN"190"37;
"DQS9_A_C||TDQS9_A_C \B"
$PN"200"36;
"DQS9_A_T||TDQS9_A_T"
$PN"201"35;
"DQS9_B_C||TDQS9_B_C \B"
$PN"94"32;
"DQS9_B_T||TDQS9_B_T||DBI4_B_N"
$PN"93"31;
%"GND"
"1","(-2825,5225)","0","pure_quanta_power","I368";
;
ROOM"MEM_EFGH_DECOUPLING_CAPS"
CDS_LIB"pure_quanta_power"
BOM_COST"MEM"
SIZE"1B"
HDL_POWER"GND";
"A<SIZE-1..0>\NAC"165;
%"Q_CAP"
"1","(-2825,5575)","2","pure_quanta","I369";
;
LOCATION"C143"
$SEC"1"
CDS_SEC"1"
MATERIAL"X6S"
TOLERANCE"10%"
VALUE"10UF"
VOLTAGE"25V"
PACK_TYPE"C0805"
CDS_LIB"pure_quanta"
BOM_COST"MEM"
ROOM""
PART_NUMBER"CH6104KEA00";
"B"
$PN"2"165;
"A"
$PN"1"166;
%"Q_CAP"
"1","(-2250,5575)","2","pure_quanta","I370";
;
LOCATION"C145"
$SEC"1"
CDS_SEC"1"
MATERIAL"X6S"
TOLERANCE"10%"
VALUE"10UF"
VOLTAGE"25V"
PACK_TYPE"C0805"
CDS_LIB"pure_quanta"
BOM_COST"MEM"
ROOM""
PART_NUMBER"CH6104KEA00";
"B"
$PN"2"165;
"A"
$PN"1"166;
%"UNIVERSAL_POWER"
"1","(-2825,5900)","0","pure_quanta_power","I371";
;
HDL_POWER"P12V_MEM_CPU0"
CDS_LIB"pure_quanta_power"
BOM_COST"VR_SYSTEM";
"A"166;
%"Q_RES"
"1","(-7975,2775)","0","pure_quanta","I372";
;
LOCATION"R1569"
$SEC"1"
CDS_SEC"1"
VALUE"49.9"
TOLERANCE"1%"
WATTAGE"1/16W"
PACK_TYPE"0402LF"
MATERIAL"CHIP"
CDS_LIB"pure_quanta"
PART_NUMBER"CS04992FB07";
"B"
$PN"2"169;
"A"
$PN"1"16;
%"Q_RES"
"1","(-8300,2975)","0","pure_quanta","I373";
;
LOCATION"R1675"
SEC"1"
PACK_TYPE"0402LF"
MATERIAL"CHIP"
VALUE"10"
TOLERANCE"1%"
WATTAGE"1/16W"
CDS_LIB"pure_quanta"
SEC_TYPE"0402LF"
PART_NUMBER"CS01002FB07";
"B"
$PN"2"15;
"A"
$PN"1"170;
END.
